(kicad_pcb
	(version 20260206)
	(generator "pcbnew")
	(generator_version "10.0")
	(general
		(thickness 1.6)
		(legacy_teardrops no)
	)
	(paper "A4")
	(title_block
		(title "Bryce Canyon_F.DPB_16315-1-OCP.brd")
		(comment 1 "Bryce Canyon / footprints 1879-1886 of 2223")
	)
	(layers
		(0 "F.Cu" signal "TOP")
		(4 "In1.Cu" signal "L2GND")
		(6 "In2.Cu" signal "L3")
		(8 "In3.Cu" signal "L4GND")
		(10 "In4.Cu" signal "L5")
		(12 "In5.Cu" signal "L6VCC")
		(14 "In6.Cu" signal "L7VCC")
		(16 "In7.Cu" signal "L8")
		(18 "In8.Cu" signal "L9GND")
		(20 "In9.Cu" signal "L10")
		(22 "In10.Cu" signal "L11GND")
		(2 "B.Cu" signal "BOTTOM")
		(9 "F.Adhes" user "F.Adhesive")
		(11 "B.Adhes" user "B.Adhesive")
		(13 "F.Paste" user "Package Geometry/Pastemask Top")
		(15 "B.Paste" user "Package Geometry/Pastemask Bottom")
		(5 "F.SilkS" user "Ref Des/Silkscreen Top")
		(7 "B.SilkS" user "Ref Des/Silkscreen Bottom")
		(1 "F.Mask" user "Board Geometry/Soldermask Top")
		(3 "B.Mask" user "Board Geometry/Soldermask Bottom")
		(17 "Dwgs.User" user "User.Drawings")
		(19 "Cmts.User" user "User.Comments")
		(21 "Eco1.User" user "User.Eco1")
		(23 "Eco2.User" user "User.Eco2")
		(25 "Edge.Cuts" user "Board Geometry/Outline")
		(27 "Margin" user)
		(31 "F.CrtYd" user "Package Geometry/Place Bound Top")
		(29 "B.CrtYd" user "Package Geometry/Place Bound Bottom")
		(35 "F.Fab" user "Ref Des/Assembly Top")
		(33 "B.Fab" user "Ref Des/Assembly Bottom")
	)
	(footprint ""
		(layer "F.Cu")
		(at 52.031646 -161.268918 180)
		(property "Reference" "Q79"
			(at 0 0 180)
			(layer "F.SilkS")
			(hide yes)
			(effects
				(font
					(size 1.27 1.27)
				)
			)
		)
		(property "Value" "2N7002KDW-GP"
			(at -2.3622 -8.2042 180)
			(unlocked yes)
			(layer "F.Fab")
			(hide yes)
			(effects
				(font
					(size 1.016 1.016)
					(thickness 0.1524)
				)
			)
		)
		(property "Device Type" "SOT-363H44"
			(at -2.3622 -10.1092 180)
			(unlocked yes)
			(layer "F.Fab")
			(hide yes)
			(effects
				(font
					(size 1.016 1.016)
					(thickness 0.1524)
				)
			)
		)
		(duplicate_pad_numbers_are_jumpers no)
		(fp_line
			(start 1.4478 1.7018)
			(end 1.4478 -1.7018)
			(stroke
				(width 0.1524)
				(type default)
			)
			(layer "F.SilkS")
		)
		(fp_line
			(start 1.4478 -1.7018)
			(end -1.4478 -1.7018)
			(stroke
				(width 0.1524)
				(type default)
			)
			(layer "F.SilkS")
		)
		(fp_line
			(start -1.27 1.524)
			(end -1.27 0.6604)
			(stroke
				(width 0.4826)
				(type default)
			)
			(layer "F.SilkS")
		)
		(fp_line
			(start -1.4478 1.7018)
			(end 1.4478 1.7018)
			(stroke
				(width 0.1524)
				(type default)
			)
			(layer "F.SilkS")
		)
		(fp_line
			(start -1.4478 -1.7018)
			(end -1.4478 1.7018)
			(stroke
				(width 0.1524)
				(type default)
			)
			(layer "F.SilkS")
		)
		(fp_poly
			(pts
				(xy -1.524 -1.778) (xy 1.524 -1.778) (xy 1.524 1.778) (xy -1.524 1.778)
			)
			(stroke
				(width 0)
				(type default)
			)
			(fill no)
			(layer "F.CrtYd")
		)
		(fp_poly
			(pts
				(xy -1.524 -1.778) (xy 1.524 -1.778) (xy 1.524 1.778) (xy -1.524 1.778)
			)
			(stroke
				(width 0)
				(type default)
			)
			(fill no)
			(layer "F.Fab")
		)
		(pad "1" smd rect
			(at -0.65024 0.9398 180)
			(size 0.4064 1.016)
			(layers "F.Cu" "F.Mask" "F.Paste")
			(net "GND")
		)
		(pad "2" smd rect
			(at 0 0.9398 180)
			(size 0.4064 1.016)
			(layers "F.Cu" "F.Mask" "F.Paste")
			(net "SW_PWR_R_HDD13")
		)
		(pad "3" smd rect
			(at 0.65024 0.9398 180)
			(size 0.4064 1.016)
			(layers "F.Cu" "F.Mask" "F.Paste")
			(net "SW_HDD_P13")
		)
		(pad "4" smd rect
			(at 0.65024 -0.9398 180)
			(size 0.4064 1.016)
			(layers "F.Cu" "F.Mask" "F.Paste")
			(net "GND")
		)
		(pad "5" smd rect
			(at 0 -0.9398 180)
			(size 0.4064 1.016)
			(layers "F.Cu" "F.Mask" "F.Paste")
			(net "SW_HDD_G13")
		)
		(pad "6" smd rect
			(at -0.65024 -0.9398 180)
			(size 0.4064 1.016)
			(layers "F.Cu" "F.Mask" "F.Paste")
			(net "SW_HDD_R13")
		)
	)
	(footprint ""
		(layer "F.Cu")
		(at 272.321528 -17.873472 -90)
		(property "Reference" "TP250"
			(at 0 0 270)
			(layer "F.SilkS")
			(hide yes)
			(effects
				(font
					(size 1.27 1.27)
				)
			)
		)
		(property "Value" "TPAD32-GP"
			(at -0.0508 -1.6764 270)
			(unlocked yes)
			(layer "F.Fab")
			(hide yes)
			(effects
				(font
					(size 1.016 1.016)
					(thickness 0.1524)
				)
			)
		)
		(property "Device Type" "TPAD32"
			(at -0.0508 -3.2004 270)
			(unlocked yes)
			(layer "F.Fab")
			(hide yes)
			(effects
				(font
					(size 1.016 1.016)
					(thickness 0.1524)
				)
			)
		)
		(duplicate_pad_numbers_are_jumpers no)
		(fp_poly
			(pts
				(arc
					(start 0 -0.4064)
					(mid 0 0.4064)
					(end 0 -0.4064)
				)
			)
			(stroke
				(width 0)
				(type default)
			)
			(fill no)
			(layer "F.CrtYd")
		)
		(fp_poly
			(pts
				(arc
					(start 0 -0.7112)
					(mid 0 0.7112)
					(end 0 -0.7112)
				)
			)
			(stroke
				(width 0)
				(type default)
			)
			(fill no)
			(layer "F.Fab")
		)
		(pad "1" smd circle
			(at 0 0 270)
			(size 0.8128 0.8128)
			(layers "F.Cu" "F.Mask" "F.Paste")
			(net "PCIE_COMP_B_CLK_N5")
		)
	)
	(footprint ""
		(layer "F.Cu")
		(at 190.258954 -47.749968 -90)
		(property "Reference" "VIA62"
			(at 0 0 270)
			(layer "F.SilkS")
			(hide yes)
			(effects
				(font
					(size 1.27 1.27)
				)
			)
		)
		(property "Value" "100OHM-8L-1D6MM-L18L16-GP"
			(at -3.7211 -4.5085 270)
			(unlocked yes)
			(layer "F.Fab")
			(hide yes)
			(effects
				(font
					(size 1.016 1.016)
					(thickness 0.1524)
				)
			)
		)
		(property "Device Type" "VIA-PCIE-4P-394076"
			(at -3.7211 -6.0325 270)
			(unlocked yes)
			(layer "F.Fab")
			(hide yes)
			(effects
				(font
					(size 1.016 1.016)
					(thickness 0.1524)
				)
			)
		)
		(duplicate_pad_numbers_are_jumpers no)
		(fp_rect
			(start -1.9685 0.381)
			(end 1.9685 -0.381)
			(stroke
				(width 0)
				(type default)
			)
			(fill no)
			(layer "F.CrtYd")
		)
		(fp_rect
			(start -1.9685 0.381)
			(end 1.9685 -0.381)
			(stroke
				(width 0)
				(type default)
			)
			(fill no)
			(layer "F.Fab")
		)
		(pad "1" thru_hole circle
			(at -1.5875 0 270)
			(size 0.508 0.508)
			(drill 0.254)
			(layers "*.Cu" "*.Mask")
			(remove_unused_layers no)
			(net "GND")
			(clearance 0.127)
			(thermal_gap 0.127)
		)
		(pad "2" thru_hole circle
			(at -0.5715 0 270)
			(size 0.508 0.508)
			(drill 0.254)
			(layers "*.Cu" "*.Mask")
			(remove_unused_layers no)
			(net "PHY_DRV_A_TO_SCC_A_29_DP")
			(clearance 0.127)
			(thermal_gap 0.127)
		)
		(pad "3" thru_hole circle
			(at 0.5715 0 270)
			(size 0.508 0.508)
			(drill 0.254)
			(layers "*.Cu" "*.Mask")
			(remove_unused_layers no)
			(net "PHY_DRV_A_TO_SCC_A_29_DN")
			(clearance 0.127)
			(thermal_gap 0.127)
		)
		(pad "4" thru_hole circle
			(at 1.5875 0 270)
			(size 0.508 0.508)
			(drill 0.254)
			(layers "*.Cu" "*.Mask")
			(remove_unused_layers no)
			(net "GND")
			(clearance 0.127)
			(thermal_gap 0.127)
		)
	)
	(footprint ""
		(layer "F.Cu")
		(at 50.739802 -151.31415)
		(property "Reference" "R1224"
			(at 0 0 0)
			(layer "F.SilkS")
			(hide yes)
			(effects
				(font
					(size 1.27 1.27)
				)
			)
		)
		(property "Value" "49K9R2F-L-GP"
			(at 0.064008 -3.993896 0)
			(unlocked yes)
			(layer "F.Fab")
			(hide yes)
			(effects
				(font
					(size 1.016 1.016)
					(thickness 0.1524)
				)
			)
		)
		(property "Device Type" "R402H16"
			(at 0.064008 -5.517896 0)
			(unlocked yes)
			(layer "F.Fab")
			(hide yes)
			(effects
				(font
					(size 1.016 1.016)
					(thickness 0.1524)
				)
			)
		)
		(duplicate_pad_numbers_are_jumpers no)
		(fp_line
			(start -0.508 -0.9398)
			(end -0.508 0.9398)
			(stroke
				(width 0.1524)
				(type default)
			)
			(layer "F.SilkS")
		)
		(fp_line
			(start 0.508 -0.9398)
			(end -0.508 -0.9398)
			(stroke
				(width 0.1524)
				(type default)
			)
			(layer "F.SilkS")
		)
		(fp_rect
			(start -0.508 0.9398)
			(end 0.508 -0.9398)
			(stroke
				(width 0)
				(type default)
			)
			(fill no)
			(layer "F.CrtYd")
		)
		(fp_rect
			(start -0.508 0.9398)
			(end 0.508 -0.9398)
			(stroke
				(width 0)
				(type default)
			)
			(fill no)
			(layer "F.Fab")
		)
		(pad "1" smd custom
			(at 0 -0.4445)
			(size 0.1397 0.1397)
			(layers "F.Cu" "F.Mask" "F.Paste")
			(net "P12V_A")
			(options
				(clearance outline)
				(anchor circle)
			)
			(primitives
				(gr_poly
					(pts
						(arc
							(start -0.1778 -0.2794)
							(mid -0.249642 -0.249642)
							(end -0.2794 -0.1778)
						)
						(arc
							(start -0.2794 0.1778)
							(mid -0.249642 0.249642)
							(end -0.1778 0.2794)
						)
						(arc
							(start 0.1778 0.2794)
							(mid 0.249642 0.249642)
							(end 0.2794 0.1778)
						)
						(arc
							(start 0.2794 -0.1778)
							(mid 0.249642 -0.249642)
							(end 0.1778 -0.2794)
						)
					)
					(width 0)
					(fill yes)
				)
			)
		)
		(pad "2" smd custom
			(at 0 0.4445)
			(size 0.1397 0.1397)
			(layers "F.Cu" "F.Mask" "F.Paste")
			(net "P5V_B_EN_R")
			(options
				(clearance outline)
				(anchor circle)
			)
			(primitives
				(gr_poly
					(pts
						(arc
							(start -0.1778 -0.2794)
							(mid -0.249642 -0.249642)
							(end -0.2794 -0.1778)
						)
						(arc
							(start -0.2794 0.1778)
							(mid -0.249642 0.249642)
							(end -0.1778 0.2794)
						)
						(arc
							(start 0.1778 0.2794)
							(mid 0.249642 0.249642)
							(end 0.2794 0.1778)
						)
						(arc
							(start 0.2794 -0.1778)
							(mid 0.249642 -0.249642)
							(end 0.1778 -0.2794)
						)
					)
					(width 0)
					(fill yes)
				)
			)
		)
	)
	(footprint ""
		(layer "F.Cu")
		(at 143.024098 -282.060142 90)
		(property "Reference" "R229"
			(at 0 0 90)
			(layer "F.SilkS")
			(hide yes)
			(effects
				(font
					(size 1.27 1.27)
				)
			)
		)
		(property "Value" "4K7R2J-2-GP"
			(at 0.064008 -3.993896 90)
			(unlocked yes)
			(layer "F.Fab")
			(hide yes)
			(effects
				(font
					(size 1.016 1.016)
					(thickness 0.1524)
				)
			)
		)
		(property "Device Type" "R402H16"
			(at 0.064008 -5.517896 90)
			(unlocked yes)
			(layer "F.Fab")
			(hide yes)
			(effects
				(font
					(size 1.016 1.016)
					(thickness 0.1524)
				)
			)
		)
		(duplicate_pad_numbers_are_jumpers no)
		(fp_line
			(start 0.508 -0.9398)
			(end -0.508 -0.9398)
			(stroke
				(width 0.1524)
				(type default)
			)
			(layer "F.SilkS")
		)
		(fp_line
			(start -0.508 -0.9398)
			(end -0.508 0.9398)
			(stroke
				(width 0.1524)
				(type default)
			)
			(layer "F.SilkS")
		)
		(fp_rect
			(start -0.508 0.9398)
			(end 0.508 -0.9398)
			(stroke
				(width 0)
				(type default)
			)
			(fill no)
			(layer "F.CrtYd")
		)
		(fp_rect
			(start -0.508 0.9398)
			(end 0.508 -0.9398)
			(stroke
				(width 0)
				(type default)
			)
			(fill no)
			(layer "F.Fab")
		)
		(pad "1" smd custom
			(at 0 -0.4445 90)
			(size 0.1397 0.1397)
			(layers "F.Cu" "F.Mask" "F.Paste")
			(net "P12V_A")
			(options
				(clearance outline)
				(anchor circle)
			)
			(primitives
				(gr_poly
					(pts
						(arc
							(start -0.1778 -0.2794)
							(mid -0.249642 -0.249642)
							(end -0.2794 -0.1778)
						)
						(arc
							(start -0.2794 0.1778)
							(mid -0.249642 0.249642)
							(end -0.1778 0.2794)
						)
						(arc
							(start 0.1778 0.2794)
							(mid 0.249642 0.249642)
							(end 0.2794 0.1778)
						)
						(arc
							(start 0.2794 -0.1778)
							(mid 0.249642 -0.249642)
							(end 0.1778 -0.2794)
						)
					)
					(width 0)
					(fill yes)
				)
			)
		)
		(pad "2" smd custom
			(at 0 0.4445 90)
			(size 0.1397 0.1397)
			(layers "F.Cu" "F.Mask" "F.Paste")
			(net "SW_HDD_P4")
			(options
				(clearance outline)
				(anchor circle)
			)
			(primitives
				(gr_poly
					(pts
						(arc
							(start -0.1778 -0.2794)
							(mid -0.249642 -0.249642)
							(end -0.2794 -0.1778)
						)
						(arc
							(start -0.2794 0.1778)
							(mid -0.249642 0.249642)
							(end -0.1778 0.2794)
						)
						(arc
							(start 0.1778 0.2794)
							(mid 0.249642 0.249642)
							(end 0.2794 0.1778)
						)
						(arc
							(start 0.2794 -0.1778)
							(mid 0.249642 -0.249642)
							(end 0.1778 -0.2794)
						)
					)
					(width 0)
					(fill yes)
				)
			)
		)
	)
	(footprint ""
		(layer "F.Cu")
		(at 7.240524 -284.60319 90)
		(property "Reference" "R550"
			(at 0 0 90)
			(layer "F.SilkS")
			(hide yes)
			(effects
				(font
					(size 1.27 1.27)
				)
			)
		)
		(property "Value" "4K7R2J-2-GP"
			(at 0.064008 -3.993896 90)
			(unlocked yes)
			(layer "F.Fab")
			(hide yes)
			(effects
				(font
					(size 1.016 1.016)
					(thickness 0.1524)
				)
			)
		)
		(property "Device Type" "R402H16"
			(at 0.064008 -5.517896 90)
			(unlocked yes)
			(layer "F.Fab")
			(hide yes)
			(effects
				(font
					(size 1.016 1.016)
					(thickness 0.1524)
				)
			)
		)
		(duplicate_pad_numbers_are_jumpers no)
		(fp_line
			(start 0.508 -0.9398)
			(end -0.508 -0.9398)
			(stroke
				(width 0.1524)
				(type default)
			)
			(layer "F.SilkS")
		)
		(fp_line
			(start -0.508 -0.9398)
			(end -0.508 0.9398)
			(stroke
				(width 0.1524)
				(type default)
			)
			(layer "F.SilkS")
		)
		(fp_rect
			(start -0.508 0.9398)
			(end 0.508 -0.9398)
			(stroke
				(width 0)
				(type default)
			)
			(fill no)
			(layer "F.CrtYd")
		)
		(fp_rect
			(start -0.508 0.9398)
			(end 0.508 -0.9398)
			(stroke
				(width 0)
				(type default)
			)
			(fill no)
			(layer "F.Fab")
		)
		(pad "1" smd custom
			(at 0 -0.4445 90)
			(size 0.1397 0.1397)
			(layers "F.Cu" "F.Mask" "F.Paste")
			(net "DRIVE_B_24_ACT")
			(options
				(clearance outline)
				(anchor circle)
			)
			(primitives
				(gr_poly
					(pts
						(arc
							(start -0.1778 -0.2794)
							(mid -0.249642 -0.249642)
							(end -0.2794 -0.1778)
						)
						(arc
							(start -0.2794 0.1778)
							(mid -0.249642 0.249642)
							(end -0.1778 0.2794)
						)
						(arc
							(start 0.1778 0.2794)
							(mid 0.249642 0.249642)
							(end 0.2794 0.1778)
						)
						(arc
							(start 0.2794 -0.1778)
							(mid 0.249642 -0.249642)
							(end 0.1778 -0.2794)
						)
					)
					(width 0)
					(fill yes)
				)
			)
		)
		(pad "2" smd custom
			(at 0 0.4445 90)
			(size 0.1397 0.1397)
			(layers "F.Cu" "F.Mask" "F.Paste")
			(net "GND")
			(options
				(clearance outline)
				(anchor circle)
			)
			(primitives
				(gr_poly
					(pts
						(arc
							(start -0.1778 -0.2794)
							(mid -0.249642 -0.249642)
							(end -0.2794 -0.1778)
						)
						(arc
							(start -0.2794 0.1778)
							(mid -0.249642 0.249642)
							(end -0.1778 0.2794)
						)
						(arc
							(start 0.1778 0.2794)
							(mid 0.249642 0.249642)
							(end 0.2794 0.1778)
						)
						(arc
							(start 0.2794 -0.1778)
							(mid 0.249642 -0.249642)
							(end 0.1778 -0.2794)
						)
					)
					(width 0)
					(fill yes)
				)
			)
		)
	)
	(footprint ""
		(layer "F.Cu")
		(at 257.3401 -139.7 -90)
		(property "Reference" "R454"
			(at 0 0 270)
			(layer "F.SilkS")
			(hide yes)
			(effects
				(font
					(size 1.27 1.27)
				)
			)
		)
		(property "Value" "4K7R2F-GP"
			(at 0.064008 -3.993896 270)
			(unlocked yes)
			(layer "F.Fab")
			(hide yes)
			(effects
				(font
					(size 1.016 1.016)
					(thickness 0.1524)
				)
			)
		)
		(property "Device Type" "R402H16"
			(at 0.064008 -5.517896 270)
			(unlocked yes)
			(layer "F.Fab")
			(hide yes)
			(effects
				(font
					(size 1.016 1.016)
					(thickness 0.1524)
				)
			)
		)
		(duplicate_pad_numbers_are_jumpers no)
		(fp_line
			(start -0.508 -0.9398)
			(end -0.508 0.9398)
			(stroke
				(width 0.1524)
				(type default)
			)
			(layer "F.SilkS")
		)
		(fp_line
			(start 0.508 -0.9398)
			(end -0.508 -0.9398)
			(stroke
				(width 0.1524)
				(type default)
			)
			(layer "F.SilkS")
		)
		(fp_rect
			(start -0.508 0.9398)
			(end 0.508 -0.9398)
			(stroke
				(width 0)
				(type default)
			)
			(fill no)
			(layer "F.CrtYd")
		)
		(fp_rect
			(start -0.508 0.9398)
			(end 0.508 -0.9398)
			(stroke
				(width 0)
				(type default)
			)
			(fill no)
			(layer "F.Fab")
		)
		(pad "1" smd custom
			(at 0 -0.4445 270)
			(size 0.1397 0.1397)
			(layers "F.Cu" "F.Mask" "F.Paste")
			(net "GND")
			(options
				(clearance outline)
				(anchor circle)
			)
			(primitives
				(gr_poly
					(pts
						(arc
							(start -0.1778 -0.2794)
							(mid -0.249642 -0.249642)
							(end -0.2794 -0.1778)
						)
						(arc
							(start -0.2794 0.1778)
							(mid -0.249642 0.249642)
							(end -0.1778 0.2794)
						)
						(arc
							(start 0.1778 0.2794)
							(mid 0.249642 0.249642)
							(end 0.2794 0.1778)
						)
						(arc
							(start 0.2794 -0.1778)
							(mid 0.249642 -0.249642)
							(end 0.1778 -0.2794)
						)
					)
					(width 0)
					(fill yes)
				)
			)
		)
		(pad "2" smd custom
			(at 0 0.4445 270)
			(size 0.1397 0.1397)
			(layers "F.Cu" "F.Mask" "F.Paste")
			(net "COMP_A_FAST_THROTTLE_N")
			(options
				(clearance outline)
				(anchor circle)
			)
			(primitives
				(gr_poly
					(pts
						(arc
							(start -0.1778 -0.2794)
							(mid -0.249642 -0.249642)
							(end -0.2794 -0.1778)
						)
						(arc
							(start -0.2794 0.1778)
							(mid -0.249642 0.249642)
							(end -0.1778 0.2794)
						)
						(arc
							(start 0.1778 0.2794)
							(mid 0.249642 0.249642)
							(end 0.2794 0.1778)
						)
						(arc
							(start 0.2794 -0.1778)
							(mid 0.249642 -0.249642)
							(end 0.1778 -0.2794)
						)
					)
					(width 0)
					(fill yes)
				)
			)
		)
	)
	(footprint ""
		(layer "F.Cu")
		(at 364.290102 -49.596294 90)
		(property "Reference" "C451"
			(at 0 0 90)
			(layer "F.SilkS")
			(hide yes)
			(effects
				(font
					(size 1.27 1.27)
				)
			)
		)
		(property "Value" "SCD033U25V2KX-GP"
			(at 1.1811 -2.7051 90)
			(unlocked yes)
			(layer "F.Fab")
			(hide yes)
			(effects
				(font
					(size 1.016 1.016)
					(thickness 0.1524)
				)
			)
		)
		(property "Device Type" "C402H22"
			(at 1.1811 -4.2291 90)
			(unlocked yes)
			(layer "F.Fab")
			(hide yes)
			(effects
				(font
					(size 1.016 1.016)
					(thickness 0.1524)
				)
			)
		)
		(duplicate_pad_numbers_are_jumpers no)
		(fp_rect
			(start -0.4318 0.9525)
			(end 0.4318 -0.9525)
			(stroke
				(width 0)
				(type default)
			)
			(fill no)
			(layer "F.CrtYd")
		)
		(fp_rect
			(start -0.4318 0.9525)
			(end 0.4318 -0.9525)
			(stroke
				(width 0)
				(type default)
			)
			(fill no)
			(layer "F.Fab")
		)
		(pad "1" smd custom
			(at 0 -0.4445 90)
			(size 0.1524 0.1524)
			(layers "F.Cu" "F.Mask" "F.Paste")
			(net "SW_HDD_P31")
			(options
				(clearance outline)
				(anchor circle)
			)
			(primitives
				(gr_poly
					(pts
						(arc
							(start 0.3048 -0.2032)
							(mid 0.275042 -0.275042)
							(end 0.2032 -0.3048)
						)
						(arc
							(start -0.2032 -0.3048)
							(mid -0.275042 -0.275042)
							(end -0.3048 -0.2032)
						)
						(arc
							(start -0.3048 0.2032)
							(mid -0.275042 0.275042)
							(end -0.2032 0.3048)
						)
						(arc
							(start 0.2032 0.3048)
							(mid 0.275042 0.275042)
							(end 0.3048 0.2032)
						)
					)
					(width 0)
					(fill yes)
				)
			)
		)
		(pad "2" smd custom
			(at 0 0.4445 90)
			(size 0.1524 0.1524)
			(layers "F.Cu" "F.Mask" "F.Paste")
			(net "GND")
			(options
				(clearance outline)
				(anchor circle)
			)
			(primitives
				(gr_poly
					(pts
						(arc
							(start 0.3048 -0.2032)
							(mid 0.275042 -0.275042)
							(end 0.2032 -0.3048)
						)
						(arc
							(start -0.2032 -0.3048)
							(mid -0.275042 -0.275042)
							(end -0.3048 -0.2032)
						)
						(arc
							(start -0.3048 0.2032)
							(mid -0.275042 0.275042)
							(end -0.2032 0.3048)
						)
						(arc
							(start 0.2032 0.3048)
							(mid 0.275042 0.275042)
							(end 0.3048 0.2032)
						)
					)
					(width 0)
					(fill yes)
				)
			)
		)
	)
)
